(kicad_pcb
	(version 20260206)
	(generator "pcbnew")
	(generator_version "10.0")
	(general
		(thickness 1.6)
		(legacy_teardrops no)
	)
	(paper "A4")
	(title_block
		(title "Bryce Canyon_SCC_16316-1_OCP.brd")
		(comment 1 "Bryce Canyon / footprints 227-233 of 1561")
	)
	(layers
		(0 "F.Cu" signal "TOP")
		(4 "In1.Cu" signal "L2GND")
		(6 "In2.Cu" signal "L3")
		(8 "In3.Cu" signal "L4VCC")
		(10 "In4.Cu" signal "L5VCC")
		(12 "In5.Cu" signal "L6")
		(14 "In6.Cu" signal "L7GND")
		(2 "B.Cu" signal "BOTTOM")
		(9 "F.Adhes" user "F.Adhesive")
		(11 "B.Adhes" user "B.Adhesive")
		(13 "F.Paste" user "Package Geometry/Pastemask Top")
		(15 "B.Paste" user "Package Geometry/Pastemask Bottom")
		(5 "F.SilkS" user "Ref Des/Silkscreen Top")
		(7 "B.SilkS" user "Ref Des/Silkscreen Bottom")
		(1 "F.Mask" user "Board Geometry/Soldermask Top")
		(3 "B.Mask" user "Board Geometry/Soldermask Bottom")
		(17 "Dwgs.User" user "User.Drawings")
		(19 "Cmts.User" user "User.Comments")
		(21 "Eco1.User" user "User.Eco1")
		(23 "Eco2.User" user "User.Eco2")
		(25 "Edge.Cuts" user "Board Geometry/Outline")
		(27 "Margin" user)
		(31 "F.CrtYd" user "Package Geometry/Place Bound Top")
		(29 "B.CrtYd" user "Package Geometry/Place Bound Bottom")
		(35 "F.Fab" user "Ref Des/Assembly Top")
		(33 "B.Fab" user "Ref Des/Assembly Bottom")
	)
	(footprint ""
		(layer "F.Cu")
		(at 150.79726 -109.33176 90)
		(property "Reference" "R387"
			(at 0 0 90)
			(layer "F.SilkS")
			(hide yes)
			(effects
				(font
					(size 1.27 1.27)
				)
			)
		)
		(property "Value" "0R2J-2-GP"
			(at 0.064008 -3.993896 90)
			(unlocked yes)
			(layer "F.Fab")
			(hide yes)
			(effects
				(font
					(size 1.016 1.016)
					(thickness 0.1524)
				)
			)
		)
		(property "Device Type" "R402H16"
			(at 0.064008 -5.517896 90)
			(unlocked yes)
			(layer "F.Fab")
			(hide yes)
			(effects
				(font
					(size 1.016 1.016)
					(thickness 0.1524)
				)
			)
		)
		(duplicate_pad_numbers_are_jumpers no)
		(fp_line
			(start 0.508 -0.9398)
			(end -0.508 -0.9398)
			(stroke
				(width 0.1524)
				(type default)
			)
			(layer "F.SilkS")
		)
		(fp_line
			(start -0.508 -0.9398)
			(end -0.508 0.9398)
			(stroke
				(width 0.1524)
				(type default)
			)
			(layer "F.SilkS")
		)
		(fp_rect
			(start -0.508 0.9398)
			(end 0.508 -0.9398)
			(stroke
				(width 0)
				(type default)
			)
			(fill no)
			(layer "F.CrtYd")
		)
		(fp_rect
			(start -0.508 0.9398)
			(end 0.508 -0.9398)
			(stroke
				(width 0)
				(type default)
			)
			(fill no)
			(layer "F.Fab")
		)
		(pad "1" smd custom
			(at 0 -0.4445 90)
			(size 0.1397 0.1397)
			(layers "F.Cu" "F.Mask" "F.Paste")
			(net "P5V")
			(options
				(clearance outline)
				(anchor circle)
			)
			(primitives
				(gr_poly
					(pts
						(arc
							(start -0.1778 -0.2794)
							(mid -0.249642 -0.249642)
							(end -0.2794 -0.1778)
						)
						(arc
							(start -0.2794 0.1778)
							(mid -0.249642 0.249642)
							(end -0.1778 0.2794)
						)
						(arc
							(start 0.1778 0.2794)
							(mid 0.249642 0.249642)
							(end 0.2794 0.1778)
						)
						(arc
							(start 0.2794 -0.1778)
							(mid 0.249642 -0.249642)
							(end 0.1778 -0.2794)
						)
					)
					(width 0)
					(fill yes)
				)
			)
		)
		(pad "2" smd custom
			(at 0 0.4445 90)
			(size 0.1397 0.1397)
			(layers "F.Cu" "F.Mask" "F.Paste")
			(net "SDB_CONN_PWR_2")
			(options
				(clearance outline)
				(anchor circle)
			)
			(primitives
				(gr_poly
					(pts
						(arc
							(start -0.1778 -0.2794)
							(mid -0.249642 -0.249642)
							(end -0.2794 -0.1778)
						)
						(arc
							(start -0.2794 0.1778)
							(mid -0.249642 0.249642)
							(end -0.1778 0.2794)
						)
						(arc
							(start 0.1778 0.2794)
							(mid 0.249642 0.249642)
							(end 0.2794 0.1778)
						)
						(arc
							(start 0.2794 -0.1778)
							(mid 0.249642 -0.249642)
							(end 0.1778 -0.2794)
						)
					)
					(width 0)
					(fill yes)
				)
			)
		)
	)
	(footprint ""
		(layer "F.Cu")
		(at 66.421 -106.7562 90)
		(property "Reference" "R500"
			(at 0 0 90)
			(layer "F.SilkS")
			(hide yes)
			(effects
				(font
					(size 1.27 1.27)
				)
			)
		)
		(property "Value" "10KR2F-2-GP"
			(at 0.064008 -3.993896 90)
			(unlocked yes)
			(layer "F.Fab")
			(hide yes)
			(effects
				(font
					(size 1.016 1.016)
					(thickness 0.1524)
				)
			)
		)
		(property "Device Type" "R402H16"
			(at 0.064008 -5.517896 90)
			(unlocked yes)
			(layer "F.Fab")
			(hide yes)
			(effects
				(font
					(size 1.016 1.016)
					(thickness 0.1524)
				)
			)
		)
		(duplicate_pad_numbers_are_jumpers no)
		(fp_line
			(start 0.508 -0.9398)
			(end -0.508 -0.9398)
			(stroke
				(width 0.1524)
				(type default)
			)
			(layer "F.SilkS")
		)
		(fp_line
			(start -0.508 -0.9398)
			(end -0.508 0.9398)
			(stroke
				(width 0.1524)
				(type default)
			)
			(layer "F.SilkS")
		)
		(fp_rect
			(start -0.508 0.9398)
			(end 0.508 -0.9398)
			(stroke
				(width 0)
				(type default)
			)
			(fill no)
			(layer "F.CrtYd")
		)
		(fp_rect
			(start -0.508 0.9398)
			(end 0.508 -0.9398)
			(stroke
				(width 0)
				(type default)
			)
			(fill no)
			(layer "F.Fab")
		)
		(pad "1" smd custom
			(at 0 -0.4445 90)
			(size 0.1397 0.1397)
			(layers "F.Cu" "F.Mask" "F.Paste")
			(net "SCC_STBY_PGOOD_BUF")
			(options
				(clearance outline)
				(anchor circle)
			)
			(primitives
				(gr_poly
					(pts
						(arc
							(start -0.1778 -0.2794)
							(mid -0.249642 -0.249642)
							(end -0.2794 -0.1778)
						)
						(arc
							(start -0.2794 0.1778)
							(mid -0.249642 0.249642)
							(end -0.1778 0.2794)
						)
						(arc
							(start 0.1778 0.2794)
							(mid 0.249642 0.249642)
							(end 0.2794 0.1778)
						)
						(arc
							(start 0.2794 -0.1778)
							(mid 0.249642 -0.249642)
							(end 0.1778 -0.2794)
						)
					)
					(width 0)
					(fill yes)
				)
			)
		)
		(pad "2" smd custom
			(at 0 0.4445 90)
			(size 0.1397 0.1397)
			(layers "F.Cu" "F.Mask" "F.Paste")
			(net "P3V3_VREG")
			(options
				(clearance outline)
				(anchor circle)
			)
			(primitives
				(gr_poly
					(pts
						(arc
							(start -0.1778 -0.2794)
							(mid -0.249642 -0.249642)
							(end -0.2794 -0.1778)
						)
						(arc
							(start -0.2794 0.1778)
							(mid -0.249642 0.249642)
							(end -0.1778 0.2794)
						)
						(arc
							(start 0.1778 0.2794)
							(mid 0.249642 0.249642)
							(end 0.2794 0.1778)
						)
						(arc
							(start 0.2794 -0.1778)
							(mid 0.249642 -0.249642)
							(end 0.1778 -0.2794)
						)
					)
					(width 0)
					(fill yes)
				)
			)
		)
	)
	(footprint ""
		(layer "F.Cu")
		(at 8.6614 -93.6244)
		(property "Reference" "R414"
			(at 0 0 0)
			(layer "F.SilkS")
			(hide yes)
			(effects
				(font
					(size 1.27 1.27)
				)
			)
		)
		(property "Value" "1KR2F-3-GP"
			(at 0.064008 -3.993896 0)
			(unlocked yes)
			(layer "F.Fab")
			(hide yes)
			(effects
				(font
					(size 1.016 1.016)
					(thickness 0.1524)
				)
			)
		)
		(property "Device Type" "R402H16"
			(at 0.064008 -5.517896 0)
			(unlocked yes)
			(layer "F.Fab")
			(hide yes)
			(effects
				(font
					(size 1.016 1.016)
					(thickness 0.1524)
				)
			)
		)
		(duplicate_pad_numbers_are_jumpers no)
		(fp_line
			(start -0.508 -0.9398)
			(end -0.508 0.9398)
			(stroke
				(width 0.1524)
				(type default)
			)
			(layer "F.SilkS")
		)
		(fp_line
			(start 0.508 -0.9398)
			(end -0.508 -0.9398)
			(stroke
				(width 0.1524)
				(type default)
			)
			(layer "F.SilkS")
		)
		(fp_rect
			(start -0.508 0.9398)
			(end 0.508 -0.9398)
			(stroke
				(width 0)
				(type default)
			)
			(fill no)
			(layer "F.CrtYd")
		)
		(fp_rect
			(start -0.508 0.9398)
			(end 0.508 -0.9398)
			(stroke
				(width 0)
				(type default)
			)
			(fill no)
			(layer "F.Fab")
		)
		(pad "1" smd custom
			(at 0 -0.4445)
			(size 0.1397 0.1397)
			(layers "F.Cu" "F.Mask" "F.Paste")
			(net "P3V3")
			(options
				(clearance outline)
				(anchor circle)
			)
			(primitives
				(gr_poly
					(pts
						(arc
							(start -0.1778 -0.2794)
							(mid -0.249642 -0.249642)
							(end -0.2794 -0.1778)
						)
						(arc
							(start -0.2794 0.1778)
							(mid -0.249642 0.249642)
							(end -0.1778 0.2794)
						)
						(arc
							(start 0.1778 0.2794)
							(mid 0.249642 0.249642)
							(end 0.2794 0.1778)
						)
						(arc
							(start 0.2794 -0.1778)
							(mid 0.249642 -0.249642)
							(end 0.1778 -0.2794)
						)
					)
					(width 0)
					(fill yes)
				)
			)
		)
		(pad "2" smd custom
			(at 0 0.4445)
			(size 0.1397 0.1397)
			(layers "F.Cu" "F.Mask" "F.Paste")
			(net "I2C_SCC_SCL2")
			(options
				(clearance outline)
				(anchor circle)
			)
			(primitives
				(gr_poly
					(pts
						(arc
							(start -0.1778 -0.2794)
							(mid -0.249642 -0.249642)
							(end -0.2794 -0.1778)
						)
						(arc
							(start -0.2794 0.1778)
							(mid -0.249642 0.249642)
							(end -0.1778 0.2794)
						)
						(arc
							(start 0.1778 0.2794)
							(mid 0.249642 0.249642)
							(end 0.2794 0.1778)
						)
						(arc
							(start 0.2794 -0.1778)
							(mid 0.249642 -0.249642)
							(end 0.1778 -0.2794)
						)
					)
					(width 0)
					(fill yes)
				)
			)
		)
	)
	(footprint ""
		(layer "F.Cu")
		(at 51.308 -77.9272 90)
		(property "Reference" "R472"
			(at 0 0 90)
			(layer "F.SilkS")
			(hide yes)
			(effects
				(font
					(size 1.27 1.27)
				)
			)
		)
		(property "Value" "1KR2F-3-GP"
			(at 0.064008 -3.993896 90)
			(unlocked yes)
			(layer "F.Fab")
			(hide yes)
			(effects
				(font
					(size 1.016 1.016)
					(thickness 0.1524)
				)
			)
		)
		(property "Device Type" "R402H16"
			(at 0.064008 -5.517896 90)
			(unlocked yes)
			(layer "F.Fab")
			(hide yes)
			(effects
				(font
					(size 1.016 1.016)
					(thickness 0.1524)
				)
			)
		)
		(duplicate_pad_numbers_are_jumpers no)
		(fp_line
			(start 0.508 -0.9398)
			(end -0.508 -0.9398)
			(stroke
				(width 0.1524)
				(type default)
			)
			(layer "F.SilkS")
		)
		(fp_line
			(start -0.508 -0.9398)
			(end -0.508 0.9398)
			(stroke
				(width 0.1524)
				(type default)
			)
			(layer "F.SilkS")
		)
		(fp_rect
			(start -0.508 0.9398)
			(end 0.508 -0.9398)
			(stroke
				(width 0)
				(type default)
			)
			(fill no)
			(layer "F.CrtYd")
		)
		(fp_rect
			(start -0.508 0.9398)
			(end 0.508 -0.9398)
			(stroke
				(width 0)
				(type default)
			)
			(fill no)
			(layer "F.Fab")
		)
		(pad "1" smd custom
			(at 0 -0.4445 90)
			(size 0.1397 0.1397)
			(layers "F.Cu" "F.Mask" "F.Paste")
			(net "P3V3")
			(options
				(clearance outline)
				(anchor circle)
			)
			(primitives
				(gr_poly
					(pts
						(arc
							(start -0.1778 -0.2794)
							(mid -0.249642 -0.249642)
							(end -0.2794 -0.1778)
						)
						(arc
							(start -0.2794 0.1778)
							(mid -0.249642 0.249642)
							(end -0.1778 0.2794)
						)
						(arc
							(start 0.1778 0.2794)
							(mid 0.249642 0.249642)
							(end 0.2794 0.1778)
						)
						(arc
							(start 0.2794 -0.1778)
							(mid 0.249642 -0.249642)
							(end 0.1778 -0.2794)
						)
					)
					(width 0)
					(fill yes)
				)
			)
		)
		(pad "2" smd custom
			(at 0 0.4445 90)
			(size 0.1397 0.1397)
			(layers "F.Cu" "F.Mask" "F.Paste")
			(net "I2C_CLIP_SCL7")
			(options
				(clearance outline)
				(anchor circle)
			)
			(primitives
				(gr_poly
					(pts
						(arc
							(start -0.1778 -0.2794)
							(mid -0.249642 -0.249642)
							(end -0.2794 -0.1778)
						)
						(arc
							(start -0.2794 0.1778)
							(mid -0.249642 0.249642)
							(end -0.1778 0.2794)
						)
						(arc
							(start 0.1778 0.2794)
							(mid 0.249642 0.249642)
							(end 0.2794 0.1778)
						)
						(arc
							(start 0.2794 -0.1778)
							(mid 0.249642 -0.249642)
							(end 0.1778 -0.2794)
						)
					)
					(width 0)
					(fill yes)
				)
			)
		)
	)
	(footprint ""
		(layer "F.Cu")
		(at 156.43098 -110.92942)
		(property "Reference" "C697"
			(at 0 0 0)
			(layer "F.SilkS")
			(hide yes)
			(effects
				(font
					(size 1.27 1.27)
				)
			)
		)
		(property "Value" "SCD1U50V3KX-GP"
			(at 0 -2.8194 0)
			(unlocked yes)
			(layer "F.Fab")
			(hide yes)
			(effects
				(font
					(size 1.016 1.016)
					(thickness 0.1524)
				)
			)
		)
		(property "Device Type" "C603H36"
			(at 0 -4.3434 0)
			(unlocked yes)
			(layer "F.Fab")
			(hide yes)
			(effects
				(font
					(size 1.016 1.016)
					(thickness 0.1524)
				)
			)
		)
		(duplicate_pad_numbers_are_jumpers no)
		(fp_line
			(start 0.508 0)
			(end -0.508 0)
			(stroke
				(width 0.2032)
				(type default)
			)
			(layer "F.SilkS")
		)
		(fp_rect
			(start -0.5842 1.3335)
			(end 0.5842 -1.3335)
			(stroke
				(width 0)
				(type default)
			)
			(fill no)
			(layer "F.CrtYd")
		)
		(fp_rect
			(start -0.5842 1.3335)
			(end 0.5842 -1.3335)
			(stroke
				(width 0)
				(type default)
			)
			(fill no)
			(layer "F.Fab")
		)
		(pad "1" smd custom
			(at 0 -0.762)
			(size 0.2159 0.2159)
			(layers "F.Cu" "F.Mask" "F.Paste")
			(net "P12V_STBY_VIN_U11")
			(options
				(clearance outline)
				(anchor circle)
			)
			(primitives
				(gr_poly
					(pts
						(arc
							(start -0.3302 -0.4318)
							(mid -0.402042 -0.402042)
							(end -0.4318 -0.3302)
						)
						(arc
							(start -0.4318 0.3302)
							(mid -0.402042 0.402042)
							(end -0.3302 0.4318)
						)
						(arc
							(start 0.3302 0.4318)
							(mid 0.402042 0.402042)
							(end 0.4318 0.3302)
						)
						(arc
							(start 0.4318 -0.3302)
							(mid 0.402042 -0.402042)
							(end 0.3302 -0.4318)
						)
					)
					(width 0)
					(fill yes)
				)
			)
		)
		(pad "2" smd custom
			(at 0 0.762)
			(size 0.2159 0.2159)
			(layers "F.Cu" "F.Mask" "F.Paste")
			(net "GND")
			(options
				(clearance outline)
				(anchor circle)
			)
			(primitives
				(gr_poly
					(pts
						(arc
							(start -0.3302 -0.4318)
							(mid -0.402042 -0.402042)
							(end -0.4318 -0.3302)
						)
						(arc
							(start -0.4318 0.3302)
							(mid -0.402042 0.402042)
							(end -0.3302 0.4318)
						)
						(arc
							(start 0.3302 0.4318)
							(mid 0.402042 0.402042)
							(end 0.4318 0.3302)
						)
						(arc
							(start 0.4318 -0.3302)
							(mid 0.402042 -0.402042)
							(end 0.3302 -0.4318)
						)
					)
					(width 0)
					(fill yes)
				)
			)
		)
	)
	(footprint ""
		(layer "F.Cu")
		(at 157.8737 -89.7636 -90)
		(property "Reference" "R330"
			(at 0 0 270)
			(layer "F.SilkS")
			(hide yes)
			(effects
				(font
					(size 1.27 1.27)
				)
			)
		)
		(property "Value" "4K7R2F-GP"
			(at 0.064008 -3.993896 270)
			(unlocked yes)
			(layer "F.Fab")
			(hide yes)
			(effects
				(font
					(size 1.016 1.016)
					(thickness 0.1524)
				)
			)
		)
		(property "Device Type" "R402H16"
			(at 0.064008 -5.517896 270)
			(unlocked yes)
			(layer "F.Fab")
			(hide yes)
			(effects
				(font
					(size 1.016 1.016)
					(thickness 0.1524)
				)
			)
		)
		(duplicate_pad_numbers_are_jumpers no)
		(fp_line
			(start -0.508 -0.9398)
			(end -0.508 0.9398)
			(stroke
				(width 0.1524)
				(type default)
			)
			(layer "F.SilkS")
		)
		(fp_line
			(start 0.508 -0.9398)
			(end -0.508 -0.9398)
			(stroke
				(width 0.1524)
				(type default)
			)
			(layer "F.SilkS")
		)
		(fp_rect
			(start -0.508 0.9398)
			(end 0.508 -0.9398)
			(stroke
				(width 0)
				(type default)
			)
			(fill no)
			(layer "F.CrtYd")
		)
		(fp_rect
			(start -0.508 0.9398)
			(end 0.508 -0.9398)
			(stroke
				(width 0)
				(type default)
			)
			(fill no)
			(layer "F.Fab")
		)
		(pad "1" smd custom
			(at 0 -0.4445 270)
			(size 0.1397 0.1397)
			(layers "F.Cu" "F.Mask" "F.Paste")
			(net "P3V3")
			(options
				(clearance outline)
				(anchor circle)
			)
			(primitives
				(gr_poly
					(pts
						(arc
							(start -0.1778 -0.2794)
							(mid -0.249642 -0.249642)
							(end -0.2794 -0.1778)
						)
						(arc
							(start -0.2794 0.1778)
							(mid -0.249642 0.249642)
							(end -0.1778 0.2794)
						)
						(arc
							(start 0.1778 0.2794)
							(mid 0.249642 0.249642)
							(end 0.2794 0.1778)
						)
						(arc
							(start 0.2794 -0.1778)
							(mid 0.249642 -0.249642)
							(end 0.1778 -0.2794)
						)
					)
					(width 0)
					(fill yes)
				)
			)
		)
		(pad "2" smd custom
			(at 0 0.4445 270)
			(size 0.1397 0.1397)
			(layers "F.Cu" "F.Mask" "F.Paste")
			(net "VOL_SEN1_ADDR")
			(options
				(clearance outline)
				(anchor circle)
			)
			(primitives
				(gr_poly
					(pts
						(arc
							(start -0.1778 -0.2794)
							(mid -0.249642 -0.249642)
							(end -0.2794 -0.1778)
						)
						(arc
							(start -0.2794 0.1778)
							(mid -0.249642 0.249642)
							(end -0.1778 0.2794)
						)
						(arc
							(start 0.1778 0.2794)
							(mid 0.249642 0.249642)
							(end 0.2794 0.1778)
						)
						(arc
							(start 0.2794 -0.1778)
							(mid 0.249642 -0.249642)
							(end 0.1778 -0.2794)
						)
					)
					(width 0)
					(fill yes)
				)
			)
		)
	)
	(footprint ""
		(layer "F.Cu")
		(at 10.652252 -59.360816 180)
		(property "Reference" "R12"
			(at 0 0 180)
			(layer "F.SilkS")
			(hide yes)
			(effects
				(font
					(size 1.27 1.27)
				)
			)
		)
		(property "Value" "0R2J-2-GP"
			(at 0.064008 -3.993896 180)
			(unlocked yes)
			(layer "F.Fab")
			(hide yes)
			(effects
				(font
					(size 1.016 1.016)
					(thickness 0.1524)
				)
			)
		)
		(property "Device Type" "R402H16"
			(at 0.064008 -5.517896 180)
			(unlocked yes)
			(layer "F.Fab")
			(hide yes)
			(effects
				(font
					(size 1.016 1.016)
					(thickness 0.1524)
				)
			)
		)
		(duplicate_pad_numbers_are_jumpers no)
		(fp_line
			(start 0.508 -0.9398)
			(end -0.508 -0.9398)
			(stroke
				(width 0.1524)
				(type default)
			)
			(layer "F.SilkS")
		)
		(fp_line
			(start -0.508 -0.9398)
			(end -0.508 0.9398)
			(stroke
				(width 0.1524)
				(type default)
			)
			(layer "F.SilkS")
		)
		(fp_rect
			(start -0.508 0.9398)
			(end 0.508 -0.9398)
			(stroke
				(width 0)
				(type default)
			)
			(fill no)
			(layer "F.CrtYd")
		)
		(fp_rect
			(start -0.508 0.9398)
			(end 0.508 -0.9398)
			(stroke
				(width 0)
				(type default)
			)
			(fill no)
			(layer "F.Fab")
		)
		(pad "1" smd custom
			(at 0 -0.4445 180)
			(size 0.1397 0.1397)
			(layers "F.Cu" "F.Mask" "F.Paste")
			(net "HSW_SCL_2")
			(options
				(clearance outline)
				(anchor circle)
			)
			(primitives
				(gr_poly
					(pts
						(arc
							(start -0.1778 -0.2794)
							(mid -0.249642 -0.249642)
							(end -0.2794 -0.1778)
						)
						(arc
							(start -0.2794 0.1778)
							(mid -0.249642 0.249642)
							(end -0.1778 0.2794)
						)
						(arc
							(start 0.1778 0.2794)
							(mid 0.249642 0.249642)
							(end 0.2794 0.1778)
						)
						(arc
							(start 0.2794 -0.1778)
							(mid 0.249642 -0.249642)
							(end 0.1778 -0.2794)
						)
					)
					(width 0)
					(fill yes)
				)
			)
		)
		(pad "2" smd custom
			(at 0 0.4445 180)
			(size 0.1397 0.1397)
			(layers "F.Cu" "F.Mask" "F.Paste")
			(net "I2C_SCC_SCL2")
			(options
				(clearance outline)
				(anchor circle)
			)
			(primitives
				(gr_poly
					(pts
						(arc
							(start -0.1778 -0.2794)
							(mid -0.249642 -0.249642)
							(end -0.2794 -0.1778)
						)
						(arc
							(start -0.2794 0.1778)
							(mid -0.249642 0.249642)
							(end -0.1778 0.2794)
						)
						(arc
							(start 0.1778 0.2794)
							(mid 0.249642 0.249642)
							(end 0.2794 0.1778)
						)
						(arc
							(start 0.2794 -0.1778)
							(mid 0.249642 -0.249642)
							(end 0.1778 -0.2794)
						)
					)
					(width 0)
					(fill yes)
				)
			)
		)
	)
)
